(kicad_pcb
	(version 20260206)
	(generator "pcbnew")
	(generator_version "10.0")
	(general
		(thickness 1.6)
		(legacy_teardrops no)
	)
	(paper "A4")
	(title_block
		(title "Bryce Canyon_SCC_16316-1_OCP.brd")
		(comment 1 "Bryce Canyon / footprints 1097-1105 of 1561")
	)
	(layers
		(0 "F.Cu" signal "TOP")
		(4 "In1.Cu" signal "L2GND")
		(6 "In2.Cu" signal "L3")
		(8 "In3.Cu" signal "L4VCC")
		(10 "In4.Cu" signal "L5VCC")
		(12 "In5.Cu" signal "L6")
		(14 "In6.Cu" signal "L7GND")
		(2 "B.Cu" signal "BOTTOM")
		(9 "F.Adhes" user "F.Adhesive")
		(11 "B.Adhes" user "B.Adhesive")
		(13 "F.Paste" user "Package Geometry/Pastemask Top")
		(15 "B.Paste" user "Package Geometry/Pastemask Bottom")
		(5 "F.SilkS" user "Ref Des/Silkscreen Top")
		(7 "B.SilkS" user "Ref Des/Silkscreen Bottom")
		(1 "F.Mask" user "Board Geometry/Soldermask Top")
		(3 "B.Mask" user "Board Geometry/Soldermask Bottom")
		(17 "Dwgs.User" user "User.Drawings")
		(19 "Cmts.User" user "User.Comments")
		(21 "Eco1.User" user "User.Eco1")
		(23 "Eco2.User" user "User.Eco2")
		(25 "Edge.Cuts" user "Board Geometry/Outline")
		(27 "Margin" user)
		(31 "F.CrtYd" user "Package Geometry/Place Bound Top")
		(29 "B.CrtYd" user "Package Geometry/Place Bound Bottom")
		(35 "F.Fab" user "Ref Des/Assembly Top")
		(33 "B.Fab" user "Ref Des/Assembly Bottom")
	)
	(footprint ""
		(layer "B.Cu")
		(at 122.4788 -69.4944 -90)
		(property "Reference" "C589"
			(at 0 0 90)
			(layer "B.SilkS")
			(hide yes)
			(effects
				(font
					(size 1.27 1.27)
				)
				(justify mirror)
			)
		)
		(property "Value" "SCD1U6D3V1KX-GP"
			(at 2.8321 -1.7399 270)
			(unlocked yes)
			(layer "B.Fab")
			(hide yes)
			(effects
				(font
					(size 1.016 1.016)
					(thickness 0.1524)
				)
				(justify mirror)
			)
		)
		(property "Device Type" "C0201H13"
			(at 2.8321 -3.2639 270)
			(unlocked yes)
			(layer "B.Fab")
			(hide yes)
			(effects
				(font
					(size 1.016 1.016)
					(thickness 0.1524)
				)
				(justify mirror)
			)
		)
		(duplicate_pad_numbers_are_jumpers no)
		(fp_rect
			(start 0.2794 0.6477)
			(end -0.2794 -0.6477)
			(stroke
				(width 0)
				(type default)
			)
			(fill no)
			(layer "B.CrtYd")
		)
		(fp_rect
			(start 0.2794 0.6477)
			(end -0.2794 -0.6477)
			(stroke
				(width 0)
				(type default)
			)
			(fill no)
			(layer "B.Fab")
		)
		(pad "1" smd custom
			(at 0 -0.2794 90)
			(size 0.0762 0.0762)
			(layers "B.Cu" "B.Mask" "B.Paste")
			(net "GB_VDDA")
			(options
				(clearance outline)
				(anchor circle)
			)
			(primitives
				(gr_poly
					(pts
						(arc
							(start 0.1524 0.127)
							(mid 0.137521 0.162921)
							(end 0.1016 0.1778)
						)
						(arc
							(start -0.1016 0.1778)
							(mid -0.137521 0.162921)
							(end -0.1524 0.127)
						)
						(arc
							(start -0.1524 -0.127)
							(mid -0.137521 -0.162921)
							(end -0.1016 -0.1778)
						)
						(arc
							(start 0.1016 -0.1778)
							(mid 0.137521 -0.162921)
							(end 0.1524 -0.127)
						)
					)
					(width 0)
					(fill yes)
				)
			)
		)
		(pad "2" smd custom
			(at 0 0.2794 90)
			(size 0.0762 0.0762)
			(layers "B.Cu" "B.Mask" "B.Paste")
			(net "GND")
			(options
				(clearance outline)
				(anchor circle)
			)
			(primitives
				(gr_poly
					(pts
						(arc
							(start 0.1524 0.127)
							(mid 0.137521 0.162921)
							(end 0.1016 0.1778)
						)
						(arc
							(start -0.1016 0.1778)
							(mid -0.137521 0.162921)
							(end -0.1524 0.127)
						)
						(arc
							(start -0.1524 -0.127)
							(mid -0.137521 -0.162921)
							(end -0.1016 -0.1778)
						)
						(arc
							(start 0.1016 -0.1778)
							(mid 0.137521 -0.162921)
							(end 0.1524 -0.127)
						)
					)
					(width 0)
					(fill yes)
				)
			)
		)
	)
	(footprint ""
		(layer "B.Cu")
		(at 118.49989 -77.499972)
		(property "Reference" "TP25"
			(at 0 0 0)
			(layer "B.SilkS")
			(hide yes)
			(effects
				(font
					(size 1.27 1.27)
				)
				(justify mirror)
			)
		)
		(property "Value" "TPAD28-2-GP"
			(at 0.0127 -1.6637 0)
			(unlocked yes)
			(layer "B.Fab")
			(hide yes)
			(effects
				(font
					(size 1.016 1.016)
					(thickness 0.1524)
				)
				(justify mirror)
			)
		)
		(property "Device Type" "TPAD28"
			(at 0.0127 -3.1877 0)
			(unlocked yes)
			(layer "B.Fab")
			(hide yes)
			(effects
				(font
					(size 1.016 1.016)
					(thickness 0.1524)
				)
				(justify mirror)
			)
		)
		(duplicate_pad_numbers_are_jumpers no)
		(fp_poly
			(pts
				(arc
					(start 0.3556 0)
					(mid -0.3556 0)
					(end 0.3556 0)
				)
			)
			(stroke
				(width 0)
				(type default)
			)
			(fill no)
			(layer "B.CrtYd")
		)
		(fp_poly
			(pts
				(arc
					(start 0.6096 0)
					(mid -0.6096 0)
					(end 0.6096 0)
				)
			)
			(stroke
				(width 0)
				(type default)
			)
			(fill no)
			(layer "B.Fab")
		)
		(pad "1" smd circle
			(at 0 0 180)
			(size 0.7112 0.7112)
			(layers "B.Cu" "B.Mask" "B.Paste")
			(net "EXP_GPIO1")
		)
	)
	(footprint ""
		(layer "B.Cu")
		(at 73.66 -57.277)
		(property "Reference" "C248"
			(at 0 0 0)
			(layer "B.SilkS")
			(hide yes)
			(effects
				(font
					(size 1.27 1.27)
				)
				(justify mirror)
			)
		)
		(property "Value" "SC100U6D3V6MX-GP"
			(at 0.0762 -5.1308 0)
			(unlocked yes)
			(layer "B.Fab")
			(hide yes)
			(effects
				(font
					(size 1.016 1.016)
					(thickness 0.1524)
				)
				(justify mirror)
			)
		)
		(property "Device Type" "C1206H71"
			(at 0.127 -6.6548 0)
			(unlocked yes)
			(layer "B.Fab")
			(hide yes)
			(effects
				(font
					(size 1.016 1.016)
					(thickness 0.1524)
				)
				(justify mirror)
			)
		)
		(duplicate_pad_numbers_are_jumpers no)
		(fp_line
			(start -1.016 -2.2352)
			(end -1.016 -0.8382)
			(stroke
				(width 0.1524)
				(type default)
			)
			(layer "B.SilkS")
		)
		(fp_line
			(start -1.016 0.8382)
			(end -1.016 2.2352)
			(stroke
				(width 0.1524)
				(type default)
			)
			(layer "B.SilkS")
		)
		(fp_line
			(start -1.016 2.2352)
			(end 1.016 2.2352)
			(stroke
				(width 0.1524)
				(type default)
			)
			(layer "B.SilkS")
		)
		(fp_line
			(start 1.016 -2.2352)
			(end -1.016 -2.2352)
			(stroke
				(width 0.1524)
				(type default)
			)
			(layer "B.SilkS")
		)
		(fp_line
			(start 1.016 -0.8382)
			(end 1.016 -2.2352)
			(stroke
				(width 0.1524)
				(type default)
			)
			(layer "B.SilkS")
		)
		(fp_line
			(start 1.016 2.2352)
			(end 1.016 0.8382)
			(stroke
				(width 0.1524)
				(type default)
			)
			(layer "B.SilkS")
		)
		(fp_rect
			(start 1.0922 2.3114)
			(end -1.0922 -2.3114)
			(stroke
				(width 0)
				(type default)
			)
			(fill no)
			(layer "B.CrtYd")
		)
		(fp_poly
			(pts
				(xy -1.0922 -2.3114) (xy -1.0922 2.3114) (xy 1.0922 2.3114) (xy 1.0922 -2.3114)
			)
			(stroke
				(width 0)
				(type default)
			)
			(fill no)
			(layer "B.Fab")
		)
		(pad "1" smd rect
			(at 0 -1.397 180)
			(size 1.651 1.27)
			(layers "B.Cu" "B.Mask" "B.Paste")
			(net "GB_VDDA")
		)
		(pad "2" smd rect
			(at 0 1.397 180)
			(size 1.651 1.27)
			(layers "B.Cu" "B.Mask" "B.Paste")
			(net "GND")
		)
	)
	(footprint ""
		(layer "B.Cu")
		(at 175.2854 -35.56)
		(property "Reference" "C419"
			(at 0 0 0)
			(layer "B.SilkS")
			(hide yes)
			(effects
				(font
					(size 1.27 1.27)
				)
				(justify mirror)
			)
		)
		(property "Value" "SCD1U6D3V1KX-GP"
			(at 2.8321 -1.7399 0)
			(unlocked yes)
			(layer "B.Fab")
			(hide yes)
			(effects
				(font
					(size 1.016 1.016)
					(thickness 0.1524)
				)
				(justify mirror)
			)
		)
		(property "Device Type" "C0201H13"
			(at 2.8321 -3.2639 0)
			(unlocked yes)
			(layer "B.Fab")
			(hide yes)
			(effects
				(font
					(size 1.016 1.016)
					(thickness 0.1524)
				)
				(justify mirror)
			)
		)
		(duplicate_pad_numbers_are_jumpers no)
		(fp_rect
			(start 0.2794 0.6477)
			(end -0.2794 -0.6477)
			(stroke
				(width 0)
				(type default)
			)
			(fill no)
			(layer "B.CrtYd")
		)
		(fp_rect
			(start 0.2794 0.6477)
			(end -0.2794 -0.6477)
			(stroke
				(width 0)
				(type default)
			)
			(fill no)
			(layer "B.Fab")
		)
		(pad "1" smd custom
			(at 0 -0.2794 180)
			(size 0.0762 0.0762)
			(layers "B.Cu" "B.Mask" "B.Paste")
			(net "P0V975")
			(options
				(clearance outline)
				(anchor circle)
			)
			(primitives
				(gr_poly
					(pts
						(arc
							(start 0.1524 0.127)
							(mid 0.137521 0.162921)
							(end 0.1016 0.1778)
						)
						(arc
							(start -0.1016 0.1778)
							(mid -0.137521 0.162921)
							(end -0.1524 0.127)
						)
						(arc
							(start -0.1524 -0.127)
							(mid -0.137521 -0.162921)
							(end -0.1016 -0.1778)
						)
						(arc
							(start 0.1016 -0.1778)
							(mid 0.137521 -0.162921)
							(end 0.1524 -0.127)
						)
					)
					(width 0)
					(fill yes)
				)
			)
		)
		(pad "2" smd custom
			(at 0 0.2794 180)
			(size 0.0762 0.0762)
			(layers "B.Cu" "B.Mask" "B.Paste")
			(net "GND")
			(options
				(clearance outline)
				(anchor circle)
			)
			(primitives
				(gr_poly
					(pts
						(arc
							(start 0.1524 0.127)
							(mid 0.137521 0.162921)
							(end 0.1016 0.1778)
						)
						(arc
							(start -0.1016 0.1778)
							(mid -0.137521 0.162921)
							(end -0.1524 0.127)
						)
						(arc
							(start -0.1524 -0.127)
							(mid -0.137521 -0.162921)
							(end -0.1016 -0.1778)
						)
						(arc
							(start 0.1016 -0.1778)
							(mid 0.137521 -0.162921)
							(end 0.1524 -0.127)
						)
					)
					(width 0)
					(fill yes)
				)
			)
		)
	)
	(footprint ""
		(layer "B.Cu")
		(at 98.171 -44.2214 180)
		(property "Reference" "C86"
			(at 0 0 0)
			(layer "B.SilkS")
			(hide yes)
			(effects
				(font
					(size 1.27 1.27)
				)
				(justify mirror)
			)
		)
		(property "Value" "SCD01U16V1KX-GP"
			(at 2.8321 -1.7399 180)
			(unlocked yes)
			(layer "B.Fab")
			(hide yes)
			(effects
				(font
					(size 1.016 1.016)
					(thickness 0.1524)
				)
				(justify mirror)
			)
		)
		(property "Device Type" "C0201H13"
			(at 2.8321 -3.2639 180)
			(unlocked yes)
			(layer "B.Fab")
			(hide yes)
			(effects
				(font
					(size 1.016 1.016)
					(thickness 0.1524)
				)
				(justify mirror)
			)
		)
		(duplicate_pad_numbers_are_jumpers no)
		(fp_rect
			(start 0.2794 0.6477)
			(end -0.2794 -0.6477)
			(stroke
				(width 0)
				(type default)
			)
			(fill no)
			(layer "B.CrtYd")
		)
		(fp_rect
			(start 0.2794 0.6477)
			(end -0.2794 -0.6477)
			(stroke
				(width 0)
				(type default)
			)
			(fill no)
			(layer "B.Fab")
		)
		(pad "1" smd custom
			(at 0 -0.2794)
			(size 0.0762 0.0762)
			(layers "B.Cu" "B.Mask" "B.Paste")
			(net "PHY_DPB_TO_SCC_17_DN")
			(options
				(clearance outline)
				(anchor circle)
			)
			(primitives
				(gr_poly
					(pts
						(arc
							(start 0.1524 0.127)
							(mid 0.137521 0.162921)
							(end 0.1016 0.1778)
						)
						(arc
							(start -0.1016 0.1778)
							(mid -0.137521 0.162921)
							(end -0.1524 0.127)
						)
						(arc
							(start -0.1524 -0.127)
							(mid -0.137521 -0.162921)
							(end -0.1016 -0.1778)
						)
						(arc
							(start 0.1016 -0.1778)
							(mid 0.137521 -0.162921)
							(end 0.1524 -0.127)
						)
					)
					(width 0)
					(fill yes)
				)
			)
		)
		(pad "2" smd custom
			(at 0 0.2794)
			(size 0.0762 0.0762)
			(layers "B.Cu" "B.Mask" "B.Paste")
			(net "PHY_DPB_TO_SCC_C_17_DN")
			(options
				(clearance outline)
				(anchor circle)
			)
			(primitives
				(gr_poly
					(pts
						(arc
							(start 0.1524 0.127)
							(mid 0.137521 0.162921)
							(end 0.1016 0.1778)
						)
						(arc
							(start -0.1016 0.1778)
							(mid -0.137521 0.162921)
							(end -0.1524 0.127)
						)
						(arc
							(start -0.1524 -0.127)
							(mid -0.137521 -0.162921)
							(end -0.1016 -0.1778)
						)
						(arc
							(start 0.1016 -0.1778)
							(mid 0.137521 -0.162921)
							(end 0.1524 -0.127)
						)
					)
					(width 0)
					(fill yes)
				)
			)
		)
	)
	(footprint ""
		(layer "B.Cu")
		(at 124.5108 -58.3946 90)
		(property "Reference" "C293"
			(at 0 0 90)
			(layer "B.SilkS")
			(hide yes)
			(effects
				(font
					(size 1.27 1.27)
				)
				(justify mirror)
			)
		)
		(property "Value" "SCD1U6D3V1KX-GP"
			(at 2.8321 -1.7399 90)
			(unlocked yes)
			(layer "B.Fab")
			(hide yes)
			(effects
				(font
					(size 1.016 1.016)
					(thickness 0.1524)
				)
				(justify mirror)
			)
		)
		(property "Device Type" "C0201H13"
			(at 2.8321 -3.2639 90)
			(unlocked yes)
			(layer "B.Fab")
			(hide yes)
			(effects
				(font
					(size 1.016 1.016)
					(thickness 0.1524)
				)
				(justify mirror)
			)
		)
		(duplicate_pad_numbers_are_jumpers no)
		(fp_rect
			(start 0.2794 0.6477)
			(end -0.2794 -0.6477)
			(stroke
				(width 0)
				(type default)
			)
			(fill no)
			(layer "B.CrtYd")
		)
		(fp_rect
			(start 0.2794 0.6477)
			(end -0.2794 -0.6477)
			(stroke
				(width 0)
				(type default)
			)
			(fill no)
			(layer "B.Fab")
		)
		(pad "1" smd custom
			(at 0 -0.2794 270)
			(size 0.0762 0.0762)
			(layers "B.Cu" "B.Mask" "B.Paste")
			(net "GB_VDDA")
			(options
				(clearance outline)
				(anchor circle)
			)
			(primitives
				(gr_poly
					(pts
						(arc
							(start 0.1524 0.127)
							(mid 0.137521 0.162921)
							(end 0.1016 0.1778)
						)
						(arc
							(start -0.1016 0.1778)
							(mid -0.137521 0.162921)
							(end -0.1524 0.127)
						)
						(arc
							(start -0.1524 -0.127)
							(mid -0.137521 -0.162921)
							(end -0.1016 -0.1778)
						)
						(arc
							(start 0.1016 -0.1778)
							(mid 0.137521 -0.162921)
							(end 0.1524 -0.127)
						)
					)
					(width 0)
					(fill yes)
				)
			)
		)
		(pad "2" smd custom
			(at 0 0.2794 270)
			(size 0.0762 0.0762)
			(layers "B.Cu" "B.Mask" "B.Paste")
			(net "GND")
			(options
				(clearance outline)
				(anchor circle)
			)
			(primitives
				(gr_poly
					(pts
						(arc
							(start 0.1524 0.127)
							(mid 0.137521 0.162921)
							(end 0.1016 0.1778)
						)
						(arc
							(start -0.1016 0.1778)
							(mid -0.137521 0.162921)
							(end -0.1524 0.127)
						)
						(arc
							(start -0.1524 -0.127)
							(mid -0.137521 -0.162921)
							(end -0.1016 -0.1778)
						)
						(arc
							(start 0.1016 -0.1778)
							(mid 0.137521 -0.162921)
							(end 0.1524 -0.127)
						)
					)
					(width 0)
					(fill yes)
				)
			)
		)
	)
	(footprint ""
		(layer "B.Cu")
		(at 181.87416 -44.785788)
		(property "Reference" "TP150"
			(at 0 0 0)
			(layer "B.SilkS")
			(hide yes)
			(effects
				(font
					(size 1.27 1.27)
				)
				(justify mirror)
			)
		)
		(property "Value" "TPAD28-2-GP"
			(at 0.0127 -1.6637 0)
			(unlocked yes)
			(layer "B.Fab")
			(hide yes)
			(effects
				(font
					(size 1.016 1.016)
					(thickness 0.1524)
				)
				(justify mirror)
			)
		)
		(property "Device Type" "TPAD28"
			(at 0.0127 -3.1877 0)
			(unlocked yes)
			(layer "B.Fab")
			(hide yes)
			(effects
				(font
					(size 1.016 1.016)
					(thickness 0.1524)
				)
				(justify mirror)
			)
		)
		(duplicate_pad_numbers_are_jumpers no)
		(fp_poly
			(pts
				(arc
					(start 0.3556 0)
					(mid -0.3556 0)
					(end 0.3556 0)
				)
			)
			(stroke
				(width 0)
				(type default)
			)
			(fill no)
			(layer "B.CrtYd")
		)
		(fp_poly
			(pts
				(arc
					(start 0.6096 0)
					(mid -0.6096 0)
					(end 0.6096 0)
				)
			)
			(stroke
				(width 0)
				(type default)
			)
			(fill no)
			(layer "B.Fab")
		)
		(pad "1" smd circle
			(at 0 0 180)
			(size 0.7112 0.7112)
			(layers "B.Cu" "B.Mask" "B.Paste")
			(net "VDDIO_15")
		)
	)
	(footprint ""
		(layer "B.Cu")
		(at 160.4518 -50.419)
		(property "Reference" "TP88"
			(at 0 0 0)
			(layer "B.SilkS")
			(hide yes)
			(effects
				(font
					(size 1.27 1.27)
				)
				(justify mirror)
			)
		)
		(property "Value" "TPAD28-2-GP"
			(at 0.0127 -1.6637 0)
			(unlocked yes)
			(layer "B.Fab")
			(hide yes)
			(effects
				(font
					(size 1.016 1.016)
					(thickness 0.1524)
				)
				(justify mirror)
			)
		)
		(property "Device Type" "TPAD28"
			(at 0.0127 -3.1877 0)
			(unlocked yes)
			(layer "B.Fab")
			(hide yes)
			(effects
				(font
					(size 1.016 1.016)
					(thickness 0.1524)
				)
				(justify mirror)
			)
		)
		(duplicate_pad_numbers_are_jumpers no)
		(fp_poly
			(pts
				(arc
					(start 0.3556 0)
					(mid -0.3556 0)
					(end 0.3556 0)
				)
			)
			(stroke
				(width 0)
				(type default)
			)
			(fill no)
			(layer "B.CrtYd")
		)
		(fp_poly
			(pts
				(arc
					(start 0.6096 0)
					(mid -0.6096 0)
					(end 0.6096 0)
				)
			)
			(stroke
				(width 0)
				(type default)
			)
			(fill no)
			(layer "B.Fab")
		)
		(pad "1" smd circle
			(at 0 0 180)
			(size 0.7112 0.7112)
			(layers "B.Cu" "B.Mask" "B.Paste")
			(net "SIO_CLK_1")
		)
	)
	(footprint ""
		(layer "B.Cu")
		(at 111.375444 -89.240614 90)
		(property "Reference" "R109"
			(at 0 0 90)
			(layer "B.SilkS")
			(hide yes)
			(effects
				(font
					(size 1.27 1.27)
				)
				(justify mirror)
			)
		)
		(property "Value" "4K75R2F-1-GP"
			(at -0.064008 -3.993896 90)
			(unlocked yes)
			(layer "B.Fab")
			(hide yes)
			(effects
				(font
					(size 1.016 1.016)
					(thickness 0.1524)
				)
				(justify mirror)
			)
		)
		(property "Device Type" "R402H16"
			(at -0.064008 -5.517896 90)
			(unlocked yes)
			(layer "B.Fab")
			(hide yes)
			(effects
				(font
					(size 1.016 1.016)
					(thickness 0.1524)
				)
				(justify mirror)
			)
		)
		(duplicate_pad_numbers_are_jumpers no)
		(fp_line
			(start 0.508 -0.9398)
			(end 0.508 0.9398)
			(stroke
				(width 0.1524)
				(type default)
			)
			(layer "B.SilkS")
		)
		(fp_line
			(start -0.508 -0.9398)
			(end 0.508 -0.9398)
			(stroke
				(width 0.1524)
				(type default)
			)
			(layer "B.SilkS")
		)
		(fp_rect
			(start 0.508 0.9398)
			(end -0.508 -0.9398)
			(stroke
				(width 0)
				(type default)
			)
			(fill no)
			(layer "B.CrtYd")
		)
		(fp_rect
			(start 0.508 0.9398)
			(end -0.508 -0.9398)
			(stroke
				(width 0)
				(type default)
			)
			(fill no)
			(layer "B.Fab")
		)
		(pad "1" smd custom
			(at 0 -0.4445 270)
			(size 0.1397 0.1397)
			(layers "B.Cu" "B.Mask" "B.Paste")
			(net "EXP_IDDT")
			(options
				(clearance outline)
				(anchor circle)
			)
			(primitives
				(gr_poly
					(pts
						(arc
							(start -0.1778 0.2794)
							(mid -0.249642 0.249642)
							(end -0.2794 0.1778)
						)
						(arc
							(start -0.2794 -0.1778)
							(mid -0.249642 -0.249642)
							(end -0.1778 -0.2794)
						)
						(arc
							(start 0.1778 -0.2794)
							(mid 0.249642 -0.249642)
							(end 0.2794 -0.1778)
						)
						(arc
							(start 0.2794 0.1778)
							(mid 0.249642 0.249642)
							(end 0.1778 0.2794)
						)
					)
					(width 0)
					(fill yes)
				)
			)
		)
		(pad "2" smd custom
			(at 0 0.4445 270)
			(size 0.1397 0.1397)
			(layers "B.Cu" "B.Mask" "B.Paste")
			(net "GND")
			(options
				(clearance outline)
				(anchor circle)
			)
			(primitives
				(gr_poly
					(pts
						(arc
							(start -0.1778 0.2794)
							(mid -0.249642 0.249642)
							(end -0.2794 0.1778)
						)
						(arc
							(start -0.2794 -0.1778)
							(mid -0.249642 -0.249642)
							(end -0.1778 -0.2794)
						)
						(arc
							(start 0.1778 -0.2794)
							(mid 0.249642 -0.249642)
							(end 0.2794 -0.1778)
						)
						(arc
							(start 0.2794 0.1778)
							(mid 0.249642 0.249642)
							(end 0.1778 0.2794)
						)
					)
					(width 0)
					(fill yes)
				)
			)
		)
	)
)
